(kicad_pcb
	(version 20260206)
	(generator "pcbnew")
	(generator_version "10.0")
	(general
		(thickness 1.6)
		(legacy_teardrops no)
	)
	(paper "A4")
	(title_block
		(title "fcb — Lightning_FCB_BRD.brd")
		(comment 1 "Lightning (Wiwynn / Facebook NVMe JBOF) / footprints 441-447 of 495")
	)
	(layers
		(0 "F.Cu" signal "TOP")
		(4 "In1.Cu" signal "L2GND")
		(6 "In2.Cu" signal "L3VCC")
		(2 "B.Cu" signal "BOTTOM")
		(9 "F.Adhes" user "F.Adhesive")
		(11 "B.Adhes" user "B.Adhesive")
		(13 "F.Paste" user "Package Geometry/Pastemask Top")
		(15 "B.Paste" user "Package Geometry/Pastemask Bottom")
		(5 "F.SilkS" user "Ref Des/Silkscreen Top")
		(7 "B.SilkS" user "Ref Des/Silkscreen Bottom")
		(1 "F.Mask" user "Board Geometry/Soldermask Top")
		(3 "B.Mask" user "Board Geometry/Soldermask Bottom")
		(17 "Dwgs.User" user "User.Drawings")
		(19 "Cmts.User" user "User.Comments")
		(21 "Eco1.User" user "User.Eco1")
		(23 "Eco2.User" user "User.Eco2")
		(25 "Edge.Cuts" user "Board Geometry/Outline")
		(27 "Margin" user)
		(31 "F.CrtYd" user "Package Geometry/Place Bound Top")
		(29 "B.CrtYd" user "Package Geometry/Place Bound Bottom")
		(35 "F.Fab" user "Ref Des/Assembly Top")
		(33 "B.Fab" user "Ref Des/Assembly Bottom")
	)
	(footprint ""
		(layer "F.Cu")
		(at 23.749 -375.285 180)
		(property "Reference" "PR37"
			(at 0 0 180)
			(layer "F.SilkS")
			(hide yes)
			(effects
				(font
					(size 1.27 1.27)
				)
			)
		)
		(property "Value" "4K99R2F-L-GP"
			(at 0.064008 -3.993896 180)
			(unlocked yes)
			(layer "F.Fab")
			(hide yes)
			(effects
				(font
					(size 1.016 1.016)
					(thickness 0.1524)
				)
			)
		)
		(property "Device Type" "R402H16"
			(at 0.064008 -5.517896 180)
			(unlocked yes)
			(layer "F.Fab")
			(hide yes)
			(effects
				(font
					(size 1.016 1.016)
					(thickness 0.1524)
				)
			)
		)
		(duplicate_pad_numbers_are_jumpers no)
		(fp_line
			(start 0.508 -0.9398)
			(end -0.508 -0.9398)
			(stroke
				(width 0.1524)
				(type default)
			)
			(layer "F.SilkS")
		)
		(fp_line
			(start -0.508 -0.9398)
			(end -0.508 0.9398)
			(stroke
				(width 0.1524)
				(type default)
			)
			(layer "F.SilkS")
		)
		(fp_rect
			(start -0.508 0.9398)
			(end 0.508 -0.9398)
			(stroke
				(width 0)
				(type default)
			)
			(fill no)
			(layer "F.CrtYd")
		)
		(fp_rect
			(start -0.508 0.9398)
			(end 0.508 -0.9398)
			(stroke
				(width 0)
				(type default)
			)
			(fill no)
			(layer "F.Fab")
		)
		(pad "1" smd custom
			(at 0 -0.4445 180)
			(size 0.1397 0.1397)
			(layers "F.Cu" "F.Mask" "F.Paste")
			(net "ADM1276_UV")
			(options
				(clearance outline)
				(anchor circle)
			)
			(primitives
				(gr_poly
					(pts
						(arc
							(start -0.1778 -0.2794)
							(mid -0.249642 -0.249642)
							(end -0.2794 -0.1778)
						)
						(arc
							(start -0.2794 0.1778)
							(mid -0.249642 0.249642)
							(end -0.1778 0.2794)
						)
						(arc
							(start 0.1778 0.2794)
							(mid 0.249642 0.249642)
							(end 0.2794 0.1778)
						)
						(arc
							(start 0.2794 -0.1778)
							(mid 0.249642 -0.249642)
							(end 0.1778 -0.2794)
						)
					)
					(width 0)
					(fill yes)
				)
			)
		)
		(pad "2" smd custom
			(at 0 0.4445 180)
			(size 0.1397 0.1397)
			(layers "F.Cu" "F.Mask" "F.Paste")
			(net "GND")
			(options
				(clearance outline)
				(anchor circle)
			)
			(primitives
				(gr_poly
					(pts
						(arc
							(start -0.1778 -0.2794)
							(mid -0.249642 -0.249642)
							(end -0.2794 -0.1778)
						)
						(arc
							(start -0.2794 0.1778)
							(mid -0.249642 0.249642)
							(end -0.1778 0.2794)
						)
						(arc
							(start 0.1778 0.2794)
							(mid 0.249642 0.249642)
							(end 0.2794 0.1778)
						)
						(arc
							(start 0.2794 -0.1778)
							(mid 0.249642 -0.249642)
							(end 0.1778 -0.2794)
						)
					)
					(width 0)
					(fill yes)
				)
			)
		)
	)
	(footprint ""
		(layer "F.Cu")
		(at 28.702 -194.0814 90)
		(property "Reference" "C41"
			(at 0 0 90)
			(layer "F.SilkS")
			(hide yes)
			(effects
				(font
					(size 1.27 1.27)
				)
			)
		)
		(property "Value" "SCD1U50V3KX-GP"
			(at 0 -2.8194 90)
			(unlocked yes)
			(layer "F.Fab")
			(hide yes)
			(effects
				(font
					(size 1.016 1.016)
					(thickness 0.1524)
				)
			)
		)
		(property "Device Type" "C603H36"
			(at 0 -4.3434 90)
			(unlocked yes)
			(layer "F.Fab")
			(hide yes)
			(effects
				(font
					(size 1.016 1.016)
					(thickness 0.1524)
				)
			)
		)
		(duplicate_pad_numbers_are_jumpers no)
		(fp_line
			(start 0.508 0)
			(end -0.508 0)
			(stroke
				(width 0.2032)
				(type default)
			)
			(layer "F.SilkS")
		)
		(fp_rect
			(start -0.5842 1.3335)
			(end 0.5842 -1.3335)
			(stroke
				(width 0)
				(type default)
			)
			(fill no)
			(layer "F.CrtYd")
		)
		(fp_rect
			(start -0.5842 1.3335)
			(end 0.5842 -1.3335)
			(stroke
				(width 0)
				(type default)
			)
			(fill no)
			(layer "F.Fab")
		)
		(pad "1" smd custom
			(at 0 -0.762 90)
			(size 0.2159 0.2159)
			(layers "F.Cu" "F.Mask" "F.Paste")
			(net "P12V")
			(options
				(clearance outline)
				(anchor circle)
			)
			(primitives
				(gr_poly
					(pts
						(arc
							(start -0.3302 -0.4318)
							(mid -0.402042 -0.402042)
							(end -0.4318 -0.3302)
						)
						(arc
							(start -0.4318 0.3302)
							(mid -0.402042 0.402042)
							(end -0.3302 0.4318)
						)
						(arc
							(start 0.3302 0.4318)
							(mid 0.402042 0.402042)
							(end 0.4318 0.3302)
						)
						(arc
							(start 0.4318 -0.3302)
							(mid 0.402042 -0.402042)
							(end 0.3302 -0.4318)
						)
					)
					(width 0)
					(fill yes)
				)
			)
		)
		(pad "2" smd custom
			(at 0 0.762 90)
			(size 0.2159 0.2159)
			(layers "F.Cu" "F.Mask" "F.Paste")
			(net "GND")
			(options
				(clearance outline)
				(anchor circle)
			)
			(primitives
				(gr_poly
					(pts
						(arc
							(start -0.3302 -0.4318)
							(mid -0.402042 -0.402042)
							(end -0.4318 -0.3302)
						)
						(arc
							(start -0.4318 0.3302)
							(mid -0.402042 0.402042)
							(end -0.3302 0.4318)
						)
						(arc
							(start 0.3302 0.4318)
							(mid 0.402042 0.402042)
							(end 0.4318 0.3302)
						)
						(arc
							(start 0.4318 -0.3302)
							(mid 0.402042 -0.402042)
							(end 0.3302 -0.4318)
						)
					)
					(width 0)
					(fill yes)
				)
			)
		)
	)
	(footprint ""
		(layer "F.Cu")
		(at 40.132 -146.5326)
		(property "Reference" "PR109"
			(at 0 0 0)
			(layer "F.SilkS")
			(hide yes)
			(effects
				(font
					(size 1.27 1.27)
				)
			)
		)
		(property "Value" "6K81R2F-1-GP"
			(at 0.064008 -3.993896 0)
			(unlocked yes)
			(layer "F.Fab")
			(hide yes)
			(effects
				(font
					(size 1.016 1.016)
					(thickness 0.1524)
				)
			)
		)
		(property "Device Type" "R402H16"
			(at 0.064008 -5.517896 0)
			(unlocked yes)
			(layer "F.Fab")
			(hide yes)
			(effects
				(font
					(size 1.016 1.016)
					(thickness 0.1524)
				)
			)
		)
		(duplicate_pad_numbers_are_jumpers no)
		(fp_line
			(start -0.508 -0.9398)
			(end -0.508 0.9398)
			(stroke
				(width 0.1524)
				(type default)
			)
			(layer "F.SilkS")
		)
		(fp_line
			(start 0.508 -0.9398)
			(end -0.508 -0.9398)
			(stroke
				(width 0.1524)
				(type default)
			)
			(layer "F.SilkS")
		)
		(fp_rect
			(start -0.508 0.9398)
			(end 0.508 -0.9398)
			(stroke
				(width 0)
				(type default)
			)
			(fill no)
			(layer "F.CrtYd")
		)
		(fp_rect
			(start -0.508 0.9398)
			(end 0.508 -0.9398)
			(stroke
				(width 0)
				(type default)
			)
			(fill no)
			(layer "F.Fab")
		)
		(pad "1" smd custom
			(at 0 -0.4445)
			(size 0.1397 0.1397)
			(layers "F.Cu" "F.Mask" "F.Paste")
			(net "P12V")
			(options
				(clearance outline)
				(anchor circle)
			)
			(primitives
				(gr_poly
					(pts
						(arc
							(start -0.1778 -0.2794)
							(mid -0.249642 -0.249642)
							(end -0.2794 -0.1778)
						)
						(arc
							(start -0.2794 0.1778)
							(mid -0.249642 0.249642)
							(end -0.1778 0.2794)
						)
						(arc
							(start 0.1778 0.2794)
							(mid 0.249642 0.249642)
							(end 0.2794 0.1778)
						)
						(arc
							(start 0.2794 -0.1778)
							(mid 0.249642 -0.249642)
							(end 0.1778 -0.2794)
						)
					)
					(width 0)
					(fill yes)
				)
			)
		)
		(pad "2" smd custom
			(at 0 0.4445)
			(size 0.1397 0.1397)
			(layers "F.Cu" "F.Mask" "F.Paste")
			(net "P12VL_2490_EN_1")
			(options
				(clearance outline)
				(anchor circle)
			)
			(primitives
				(gr_poly
					(pts
						(arc
							(start -0.1778 -0.2794)
							(mid -0.249642 -0.249642)
							(end -0.2794 -0.1778)
						)
						(arc
							(start -0.2794 0.1778)
							(mid -0.249642 0.249642)
							(end -0.1778 0.2794)
						)
						(arc
							(start 0.1778 0.2794)
							(mid 0.249642 0.249642)
							(end 0.2794 0.1778)
						)
						(arc
							(start 0.2794 -0.1778)
							(mid 0.249642 -0.249642)
							(end 0.1778 -0.2794)
						)
					)
					(width 0)
					(fill yes)
				)
			)
		)
	)
	(footprint ""
		(layer "F.Cu")
		(at 39.5224 -134.7978)
		(property "Reference" "PR97"
			(at 0 0 0)
			(layer "F.SilkS")
			(hide yes)
			(effects
				(font
					(size 1.27 1.27)
				)
			)
		)
		(property "Value" "0R2J-2-GP"
			(at 0.064008 -3.993896 0)
			(unlocked yes)
			(layer "F.Fab")
			(hide yes)
			(effects
				(font
					(size 1.016 1.016)
					(thickness 0.1524)
				)
			)
		)
		(property "Device Type" "R402H16"
			(at 0.064008 -5.517896 0)
			(unlocked yes)
			(layer "F.Fab")
			(hide yes)
			(effects
				(font
					(size 1.016 1.016)
					(thickness 0.1524)
				)
			)
		)
		(duplicate_pad_numbers_are_jumpers no)
		(fp_line
			(start -0.508 -0.9398)
			(end -0.508 0.9398)
			(stroke
				(width 0.1524)
				(type default)
			)
			(layer "F.SilkS")
		)
		(fp_line
			(start 0.508 -0.9398)
			(end -0.508 -0.9398)
			(stroke
				(width 0.1524)
				(type default)
			)
			(layer "F.SilkS")
		)
		(fp_rect
			(start -0.508 0.9398)
			(end 0.508 -0.9398)
			(stroke
				(width 0)
				(type default)
			)
			(fill no)
			(layer "F.CrtYd")
		)
		(fp_rect
			(start -0.508 0.9398)
			(end 0.508 -0.9398)
			(stroke
				(width 0)
				(type default)
			)
			(fill no)
			(layer "F.Fab")
		)
		(pad "1" smd custom
			(at 0 -0.4445)
			(size 0.1397 0.1397)
			(layers "F.Cu" "F.Mask" "F.Paste")
			(net "P12VL_2490_SENSE")
			(options
				(clearance outline)
				(anchor circle)
			)
			(primitives
				(gr_poly
					(pts
						(arc
							(start -0.1778 -0.2794)
							(mid -0.249642 -0.249642)
							(end -0.2794 -0.1778)
						)
						(arc
							(start -0.2794 0.1778)
							(mid -0.249642 0.249642)
							(end -0.1778 0.2794)
						)
						(arc
							(start 0.1778 0.2794)
							(mid 0.249642 0.249642)
							(end 0.2794 0.1778)
						)
						(arc
							(start 0.2794 -0.1778)
							(mid 0.249642 -0.249642)
							(end 0.1778 -0.2794)
						)
					)
					(width 0)
					(fill yes)
				)
			)
		)
		(pad "2" smd custom
			(at 0 0.4445)
			(size 0.1397 0.1397)
			(layers "F.Cu" "F.Mask" "F.Paste")
			(net "P12VL_NET")
			(options
				(clearance outline)
				(anchor circle)
			)
			(primitives
				(gr_poly
					(pts
						(arc
							(start -0.1778 -0.2794)
							(mid -0.249642 -0.249642)
							(end -0.2794 -0.1778)
						)
						(arc
							(start -0.2794 0.1778)
							(mid -0.249642 0.249642)
							(end -0.1778 0.2794)
						)
						(arc
							(start 0.1778 0.2794)
							(mid 0.249642 0.249642)
							(end 0.2794 0.1778)
						)
						(arc
							(start 0.2794 -0.1778)
							(mid 0.249642 -0.249642)
							(end 0.1778 -0.2794)
						)
					)
					(width 0)
					(fill yes)
				)
			)
		)
	)
	(footprint ""
		(layer "F.Cu")
		(at 21.766784 -215.519 90)
		(property "Reference" "R131"
			(at 0 0 90)
			(layer "F.SilkS")
			(hide yes)
			(effects
				(font
					(size 1.27 1.27)
				)
			)
		)
		(property "Value" "4K7R2F-GP"
			(at 0.064008 -3.993896 90)
			(unlocked yes)
			(layer "F.Fab")
			(hide yes)
			(effects
				(font
					(size 1.016 1.016)
					(thickness 0.1524)
				)
			)
		)
		(property "Device Type" "R402H16"
			(at 0.064008 -5.517896 90)
			(unlocked yes)
			(layer "F.Fab")
			(hide yes)
			(effects
				(font
					(size 1.016 1.016)
					(thickness 0.1524)
				)
			)
		)
		(duplicate_pad_numbers_are_jumpers no)
		(fp_line
			(start 0.508 -0.9398)
			(end -0.508 -0.9398)
			(stroke
				(width 0.1524)
				(type default)
			)
			(layer "F.SilkS")
		)
		(fp_line
			(start -0.508 -0.9398)
			(end -0.508 0.9398)
			(stroke
				(width 0.1524)
				(type default)
			)
			(layer "F.SilkS")
		)
		(fp_rect
			(start -0.508 0.9398)
			(end 0.508 -0.9398)
			(stroke
				(width 0)
				(type default)
			)
			(fill no)
			(layer "F.CrtYd")
		)
		(fp_rect
			(start -0.508 0.9398)
			(end 0.508 -0.9398)
			(stroke
				(width 0)
				(type default)
			)
			(fill no)
			(layer "F.Fab")
		)
		(pad "1" smd custom
			(at 0 -0.4445 90)
			(size 0.1397 0.1397)
			(layers "F.Cu" "F.Mask" "F.Paste")
			(net "P3V3")
			(options
				(clearance outline)
				(anchor circle)
			)
			(primitives
				(gr_poly
					(pts
						(arc
							(start -0.1778 -0.2794)
							(mid -0.249642 -0.249642)
							(end -0.2794 -0.1778)
						)
						(arc
							(start -0.2794 0.1778)
							(mid -0.249642 0.249642)
							(end -0.1778 0.2794)
						)
						(arc
							(start 0.1778 0.2794)
							(mid 0.249642 0.249642)
							(end 0.2794 0.1778)
						)
						(arc
							(start 0.2794 -0.1778)
							(mid 0.249642 -0.249642)
							(end 0.1778 -0.2794)
						)
					)
					(width 0)
					(fill yes)
				)
			)
		)
		(pad "2" smd custom
			(at 0 0.4445 90)
			(size 0.1397 0.1397)
			(layers "F.Cu" "F.Mask" "F.Paste")
			(net "PWM_OUT_FAN5")
			(options
				(clearance outline)
				(anchor circle)
			)
			(primitives
				(gr_poly
					(pts
						(arc
							(start -0.1778 -0.2794)
							(mid -0.249642 -0.249642)
							(end -0.2794 -0.1778)
						)
						(arc
							(start -0.2794 0.1778)
							(mid -0.249642 0.249642)
							(end -0.1778 0.2794)
						)
						(arc
							(start 0.1778 0.2794)
							(mid 0.249642 0.249642)
							(end 0.2794 0.1778)
						)
						(arc
							(start 0.2794 -0.1778)
							(mid 0.249642 -0.249642)
							(end 0.1778 -0.2794)
						)
					)
					(width 0)
					(fill yes)
				)
			)
		)
	)
	(footprint ""
		(layer "F.Cu")
		(at 26.6446 -167.767 180)
		(property "Reference" "R163"
			(at 0 0 180)
			(layer "F.SilkS")
			(hide yes)
			(effects
				(font
					(size 1.27 1.27)
				)
			)
		)
		(property "Value" "0R2J-2-GP"
			(at 0.064008 -3.993896 180)
			(unlocked yes)
			(layer "F.Fab")
			(hide yes)
			(effects
				(font
					(size 1.016 1.016)
					(thickness 0.1524)
				)
			)
		)
		(property "Device Type" "R402H16"
			(at 0.064008 -5.517896 180)
			(unlocked yes)
			(layer "F.Fab")
			(hide yes)
			(effects
				(font
					(size 1.016 1.016)
					(thickness 0.1524)
				)
			)
		)
		(duplicate_pad_numbers_are_jumpers no)
		(fp_line
			(start 0.508 -0.9398)
			(end -0.508 -0.9398)
			(stroke
				(width 0.1524)
				(type default)
			)
			(layer "F.SilkS")
		)
		(fp_line
			(start -0.508 -0.9398)
			(end -0.508 0.9398)
			(stroke
				(width 0.1524)
				(type default)
			)
			(layer "F.SilkS")
		)
		(fp_rect
			(start -0.508 0.9398)
			(end 0.508 -0.9398)
			(stroke
				(width 0)
				(type default)
			)
			(fill no)
			(layer "F.CrtYd")
		)
		(fp_rect
			(start -0.508 0.9398)
			(end 0.508 -0.9398)
			(stroke
				(width 0)
				(type default)
			)
			(fill no)
			(layer "F.Fab")
		)
		(pad "1" smd custom
			(at 0 -0.4445 180)
			(size 0.1397 0.1397)
			(layers "F.Cu" "F.Mask" "F.Paste")
			(net "NCT7904D_PWM3")
			(options
				(clearance outline)
				(anchor circle)
			)
			(primitives
				(gr_poly
					(pts
						(arc
							(start -0.1778 -0.2794)
							(mid -0.249642 -0.249642)
							(end -0.2794 -0.1778)
						)
						(arc
							(start -0.2794 0.1778)
							(mid -0.249642 0.249642)
							(end -0.1778 0.2794)
						)
						(arc
							(start 0.1778 0.2794)
							(mid 0.249642 0.249642)
							(end 0.2794 0.1778)
						)
						(arc
							(start 0.2794 -0.1778)
							(mid 0.249642 -0.249642)
							(end 0.1778 -0.2794)
						)
					)
					(width 0)
					(fill yes)
				)
			)
		)
		(pad "2" smd custom
			(at 0 0.4445 180)
			(size 0.1397 0.1397)
			(layers "F.Cu" "F.Mask" "F.Paste")
			(net "PWM_BUFFER_IN_FAN5_FAN6")
			(options
				(clearance outline)
				(anchor circle)
			)
			(primitives
				(gr_poly
					(pts
						(arc
							(start -0.1778 -0.2794)
							(mid -0.249642 -0.249642)
							(end -0.2794 -0.1778)
						)
						(arc
							(start -0.2794 0.1778)
							(mid -0.249642 0.249642)
							(end -0.1778 0.2794)
						)
						(arc
							(start 0.1778 0.2794)
							(mid 0.249642 0.249642)
							(end 0.2794 0.1778)
						)
						(arc
							(start 0.2794 -0.1778)
							(mid 0.249642 -0.249642)
							(end 0.1778 -0.2794)
						)
					)
					(width 0)
					(fill yes)
				)
			)
		)
	)
	(footprint ""
		(layer "F.Cu")
		(at 44.704 -158.5722 -90)
		(property "Reference" "R14"
			(at 0 0 270)
			(layer "F.SilkS")
			(hide yes)
			(effects
				(font
					(size 1.27 1.27)
				)
			)
		)
		(property "Value" "110KR2F-L-GP"
			(at 0.064008 -3.993896 270)
			(unlocked yes)
			(layer "F.Fab")
			(hide yes)
			(effects
				(font
					(size 1.016 1.016)
					(thickness 0.1524)
				)
			)
		)
		(property "Device Type" "R402H16"
			(at 0.064008 -5.517896 270)
			(unlocked yes)
			(layer "F.Fab")
			(hide yes)
			(effects
				(font
					(size 1.016 1.016)
					(thickness 0.1524)
				)
			)
		)
		(duplicate_pad_numbers_are_jumpers no)
		(fp_line
			(start -0.508 -0.9398)
			(end -0.508 0.9398)
			(stroke
				(width 0.1524)
				(type default)
			)
			(layer "F.SilkS")
		)
		(fp_line
			(start 0.508 -0.9398)
			(end -0.508 -0.9398)
			(stroke
				(width 0.1524)
				(type default)
			)
			(layer "F.SilkS")
		)
		(fp_rect
			(start -0.508 0.9398)
			(end 0.508 -0.9398)
			(stroke
				(width 0)
				(type default)
			)
			(fill no)
			(layer "F.CrtYd")
		)
		(fp_rect
			(start -0.508 0.9398)
			(end 0.508 -0.9398)
			(stroke
				(width 0)
				(type default)
			)
			(fill no)
			(layer "F.Fab")
		)
		(pad "1" smd custom
			(at 0 -0.4445 270)
			(size 0.1397 0.1397)
			(layers "F.Cu" "F.Mask" "F.Paste")
			(net "P12V_AUX")
			(options
				(clearance outline)
				(anchor circle)
			)
			(primitives
				(gr_poly
					(pts
						(arc
							(start -0.1778 -0.2794)
							(mid -0.249642 -0.249642)
							(end -0.2794 -0.1778)
						)
						(arc
							(start -0.2794 0.1778)
							(mid -0.249642 0.249642)
							(end -0.1778 0.2794)
						)
						(arc
							(start 0.1778 0.2794)
							(mid 0.249642 0.249642)
							(end 0.2794 0.1778)
						)
						(arc
							(start 0.2794 -0.1778)
							(mid 0.249642 -0.249642)
							(end 0.1778 -0.2794)
						)
					)
					(width 0)
					(fill yes)
				)
			)
		)
		(pad "2" smd custom
			(at 0 0.4445 270)
			(size 0.1397 0.1397)
			(layers "F.Cu" "F.Mask" "F.Paste")
			(net "NCT7904_VSEN_P12V_AUX")
			(options
				(clearance outline)
				(anchor circle)
			)
			(primitives
				(gr_poly
					(pts
						(arc
							(start -0.1778 -0.2794)
							(mid -0.249642 -0.249642)
							(end -0.2794 -0.1778)
						)
						(arc
							(start -0.2794 0.1778)
							(mid -0.249642 0.249642)
							(end -0.1778 0.2794)
						)
						(arc
							(start 0.1778 0.2794)
							(mid 0.249642 0.249642)
							(end 0.2794 0.1778)
						)
						(arc
							(start 0.2794 -0.1778)
							(mid 0.249642 -0.249642)
							(end 0.1778 -0.2794)
						)
					)
					(width 0)
					(fill yes)
				)
			)
		)
	)
)
